FILE_TYPE = MACRO_DRAWING;
SET COLOR_WIRE YELLOW;
SET COLOR_PROP MONO;
SET COLOR_DOT WHITE;
SET COLOR_ARC YELLOW;
SET COLOR_BODY GREEN;
SET COLOR_NOTE MONO;
SET PROP_DISPLAY VALUE;
SET PAGE_NUMBER P134;
FORCEADD OFFPAGE..2
(1875 4650);
FORCEPROP 2 LAST $XR1 144 
J 0
(2184 4650);
DISPLAY 0.638298 (2184 4650);
PAINT MONO (2184 4650);
FORCEPROP 2 LAST $XR0 120 
J 0
(2064 4650);
DISPLAY 0.638298 (2064 4650);
PAINT MONO (2064 4650);
FORCEPROP 1 LAST COMMENT_BODY TRUE
J 0
(1830 4555);
DISPLAY 0.872340 (1830 4555);
PAINT GREEN (1830 4555);
DISPLAY INVISIBLE (1830 4555);
FORCEPROP 1 LAST OFFPAGE TRUE
J 0
(2200 4525);
DISPLAY 0.872340 (2200 4525);
PAINT GREEN (2200 4525);
DISPLAY INVISIBLE (2200 4525);
FORCEPROP 2 LAST CDS_LIB mstr_standard
J 0
(1875 4650);
PAINT ORANGE (1875 4650);
DISPLAY INVISIBLE (1875 4650);
FORCEPROP 2 LAST PATH I1
J 0
(2200 4700);
DISPLAY 1.021277 (2200 4700);
PAINT ORANGE (2200 4700);
DISPLAY INVISIBLE (2200 4700);
FORCEADD RES..1
(-3950 4300);
FORCEPROP 1 LASTPIN (-4050 4300) $PN 1
J 0
(-4038 4312);
DISPLAY 0.617021 (-4038 4312);
PAINT ORANGE (-4038 4312);
FORCEPROP 1 LASTPIN (-3850 4300) $PN 2
J 0
(-3888 4312);
DISPLAY 0.617021 (-3888 4312);
PAINT ORANGE (-3888 4312);
FORCEPROP 1 LAST MATERIAL CHIP
J 0
(-3950 4150);
DISPLAY 0.617021 (-3950 4150);
PAINT SKYBLUE (-3950 4150);
FORCEPROP 1 LAST PACK_TYPE 0402
J 0
(-3700 4150);
DISPLAY 0.617021 (-3700 4150);
PAINT SKYBLUE (-3700 4150);
FORCEPROP 1 LAST TOLERANCE 1%
J 0
(-3950 4200);
DISPLAY 0.617021 (-3950 4200);
PAINT SKYBLUE (-3950 4200);
FORCEPROP 1 LAST VALUE 1.00K
J 2
(-3975 4200);
DISPLAY 0.617021 (-3975 4200);
PAINT SKYBLUE (-3975 4200);
FORCEPROP 1 LAST PART_NUMBER G21796-026
J 0
(-4000 4400);
DISPLAY 0.617021 (-4000 4400);
PAINT BLUE (-4000 4400);
FORCEPROP 1 LAST LOCATION R7D18
J 0
(-4000 4350);
DISPLAY 0.617021 (-4000 4350);
PAINT AQUA (-4000 4350);
FORCEPROP 1 LAST WATTAGE 1/16W
J 2
(-3975 4150);
DISPLAY 0.617021 (-3975 4150);
PAINT SKYBLUE (-3975 4150);
FORCEPROP 0 LAST ROOM PROC_SIDEBAND
J 0
(-4000 4500);
DISPLAY 1.021277 (-4000 4500);
PAINT ORANGE (-4000 4500);
DISPLAY INVISIBLE (-4000 4500);
FORCEPROP 2 LAST CDS_LOCATION R7D18
J 0
(-4000 4350);
DISPLAY 0.617021 (-4000 4350);
PAINT AQUA (-4000 4350);
DISPLAY INVISIBLE (-4000 4350);
FORCEPROP 2 LAST SEC 1
J 0
(-4000 4500);
DISPLAY 0.680851 (-4000 4500);
PAINT MONO (-4000 4500);
DISPLAY INVISIBLE (-4000 4500);
FORCEPROP 2 LAST CDS_LIB mstr_discrete
J 0
(-3950 4300);
PAINT ORANGE (-3950 4300);
DISPLAY INVISIBLE (-3950 4300);
FORCEPROP 2 LAST SEC_TYPE 0402
J 0
(-4000 4500);
DISPLAY 1.021277 (-4000 4500);
PAINT ORANGE (-4000 4500);
DISPLAY INVISIBLE (-4000 4500);
FORCEPROP 1 LAST PATH I11
J 0
(-4000 4450);
DISPLAY 0.978723 (-4000 4450);
PAINT WHITE (-4000 4450);
DISPLAY INVISIBLE (-4000 4450);
FORCEADD GND..1
(-2875 3950);
FORCEPROP 3 LASTPIN (-2875 4000) SIG_NAME GND\g
J 0
(-2865 4010);
DISPLAY 0.659574 (-2865 4010);
PAINT MONO (-2865 4010);
DISPLAY INVISIBLE (-2865 4010);
FORCEPROP 1 LAST HDL_POWER GND
J 0
(-2875 4100);
DISPLAY 1.468085 (-2875 4100);
PAINT GREEN (-2875 4100);
DISPLAY INVISIBLE (-2875 4100);
FORCEPROP 1 LAST BODY_TYPE PLUMBING
J 0
(-2920 3907);
DISPLAY 0.340426 (-2920 3907);
PAINT GREEN (-2920 3907);
DISPLAY INVISIBLE (-2920 3907);
FORCEPROP 1 LAST SIZE 1B
J 0
(-2800 3900);
DISPLAY 1.468085 (-2800 3900);
PAINT GREEN (-2800 3900);
DISPLAY INVISIBLE (-2800 3900);
FORCEPROP 2 LAST CDS_LIB mstr_symbols
J 0
(-2875 3950);
PAINT MONO (-2875 3950);
DISPLAY INVISIBLE (-2875 3950);
FORCEPROP 2 LAST BOM_COST SB
J 0
(-2925 4025);
PAINT MONO (-2925 4025);
DISPLAY INVISIBLE (-2925 4025);
FORCEPROP 1 LAST VOLTAGE 0
J 0
(-2875 3950);
PAINT SKYBLUE (-2875 3950);
DISPLAY INVISIBLE (-2875 3950);
FORCEPROP 1 LAST PATH I12
J 0
(-2800 3950);
DISPLAY 0.872340 (-2800 3950);
PAINT AQUA (-2800 3950);
DISPLAY INVISIBLE (-2800 3950);
FORCEADD OFFPAGE..1
(-4650 4300);
FORCEPROP 2 LASTPIN (-4600 4300) SIG_NAME FM_THERMTRIP_DLY
J 0
(-4585 4310);
DISPLAY 0.617021 (-4585 4310);
PAINT ORANGE (-4585 4310);
FORCEPROP 2 LAST $XR0 191 
J 0
(-4902 4300);
DISPLAY 0.638298 (-4902 4300);
PAINT MONO (-4902 4300);
FORCEPROP 1 LAST COMMENT_BODY TRUE
J 0
(-4525 4200);
DISPLAY 1.170213 (-4525 4200);
PAINT GREEN (-4525 4200);
DISPLAY INVISIBLE (-4525 4200);
FORCEPROP 1 LAST OFFPAGE TRUE
J 0
(-4325 4175);
PAINT GREEN (-4325 4175);
DISPLAY INVISIBLE (-4325 4175);
FORCEPROP 2 LAST BOM_COST SB
J 0
(-4900 4350);
PAINT MONO (-4900 4350);
DISPLAY INVISIBLE (-4900 4350);
FORCEPROP 2 LAST CDS_LIB mstr_standard
J 0
(-4650 4300);
PAINT MONO (-4650 4300);
DISPLAY INVISIBLE (-4650 4300);
FORCEPROP 2 LAST PATH I13
J 0
(-4900 4350);
DISPLAY 1.021277 (-4900 4350);
PAINT ORANGE (-4900 4350);
DISPLAY INVISIBLE (-4900 4350);
FORCEADD FET_N..8
(-2875 4400);
FORCEPROP 1 LAST LOCATION Q7D1
J 0
(-2675 4400);
DISPLAY 0.617021 (-2675 4400);
PAINT AQUA (-2675 4400);
FORCEPROP 1 LAST VALUE 2N7002
J 0
(-2675 4350);
DISPLAY 0.617021 (-2675 4350);
PAINT SKYBLUE (-2675 4350);
FORCEPROP 1 LAST MATERIAL FET
J 0
(-2675 4300);
DISPLAY 0.617021 (-2675 4300);
PAINT SKYBLUE (-2675 4300);
FORCEPROP 1 LAST PART_NUMBER C79254-001
J 0
(-2675 4200);
DISPLAY 0.617021 (-2675 4200);
PAINT BLUE (-2675 4200);
FORCEPROP 2 LAST CDS_LIB mstr_discrete
J 0
(-2875 4400);
PAINT MONO (-2875 4400);
DISPLAY INVISIBLE (-2875 4400);
FORCEPROP 1 LAST PATH I14
J 0
(-2675 4450);
DISPLAY 0.978723 (-2675 4450);
PAINT BLUE (-2675 4450);
DISPLAY INVISIBLE (-2675 4450);
FORCEPROP 0 LAST ROOM HOT_SWAP
J 0
(-2675 4500);
DISPLAY 1.021277 (-2675 4500);
PAINT ORANGE (-2675 4500);
DISPLAY INVISIBLE (-2675 4500);
FORCEPROP 1 LAST PACK_TYPE SOT23LF
J 0
(-2675 4250);
DISPLAY 0.978723 (-2675 4250);
PAINT SKYBLUE (-2675 4250);
DISPLAY INVISIBLE (-2675 4250);
FORCEPROP 1 LASTPIN (-2875 4200) $PN 2
J 2
(-2817 4200);
DISPLAY 0.872340 (-2817 4200);
PAINT WHITE (-2817 4200);
DISPLAY INVISIBLE (-2817 4200);
FORCEPROP 1 LASTPIN (-2875 4600) $PN 3
J 2
(-2822 4565);
DISPLAY 0.872340 (-2822 4565);
PAINT WHITE (-2822 4565);
DISPLAY INVISIBLE (-2822 4565);
FORCEPROP 1 LASTPIN (-3075 4300) $PN 1
J 2
(-3072 4315);
DISPLAY 0.872340 (-3072 4315);
PAINT WHITE (-3072 4315);
DISPLAY INVISIBLE (-3072 4315);
FORCEADD FET_N..8
(700 4375);
FORCEPROP 1 LAST PART_NUMBER C79254-001
J 0
(900 4175);
DISPLAY 0.617021 (900 4175);
PAINT BLUE (900 4175);
FORCEPROP 1 LAST MATERIAL FET
J 0
(900 4275);
DISPLAY 0.617021 (900 4275);
PAINT SKYBLUE (900 4275);
FORCEPROP 1 LAST LOCATION Q8D2
J 0
(900 4375);
DISPLAY 0.617021 (900 4375);
PAINT AQUA (900 4375);
FORCEPROP 1 LAST VALUE 2N7002
J 0
(900 4325);
DISPLAY 0.617021 (900 4325);
PAINT SKYBLUE (900 4325);
FORCEPROP 1 LAST PACK_TYPE SOT23LF
J 0
(900 4225);
DISPLAY 0.978723 (900 4225);
PAINT SKYBLUE (900 4225);
DISPLAY INVISIBLE (900 4225);
FORCEPROP 0 LAST ROOM HOT_SWAP
J 0
(900 4475);
DISPLAY 1.021277 (900 4475);
PAINT ORANGE (900 4475);
DISPLAY INVISIBLE (900 4475);
FORCEPROP 1 LAST PATH I15
J 0
(900 4425);
DISPLAY 0.978723 (900 4425);
PAINT BLUE (900 4425);
DISPLAY INVISIBLE (900 4425);
FORCEPROP 2 LAST CDS_LIB mstr_discrete
J 0
(700 4375);
PAINT MONO (700 4375);
DISPLAY INVISIBLE (700 4375);
FORCEPROP 1 LASTPIN (700 4175) $PN 2
J 2
(758 4175);
DISPLAY 0.872340 (758 4175);
PAINT WHITE (758 4175);
DISPLAY INVISIBLE (758 4175);
FORCEPROP 1 LASTPIN (700 4575) $PN 3
J 2
(753 4540);
DISPLAY 0.872340 (753 4540);
PAINT WHITE (753 4540);
DISPLAY INVISIBLE (753 4540);
FORCEPROP 1 LASTPIN (500 4275) $PN 1
J 2
(503 4290);
DISPLAY 0.872340 (503 4290);
PAINT WHITE (503 4290);
DISPLAY INVISIBLE (503 4290);
FORCEADD P3V3_STBY..1
(700 5200);
FORCEPROP 3 LASTPIN (700 5150) SIG_NAME P3V3_STBY\g
J 0
(710 5160);
DISPLAY 0.659574 (710 5160);
PAINT MONO (710 5160);
DISPLAY INVISIBLE (710 5160);
FORCEPROP 1 LAST HDL_POWER P3V3_STBY
J 0
(400 5075);
DISPLAY 0.872340 (400 5075);
PAINT ORANGE (400 5075);
DISPLAY INVISIBLE (400 5075);
FORCEPROP 1 LAST BODY_TYPE PLUMBING
J 0
(655 5157);
DISPLAY 0.340426 (655 5157);
PAINT GREEN (655 5157);
DISPLAY INVISIBLE (655 5157);
FORCEPROP 2 LAST CDS_LIB mstr_symbols
J 0
(700 5200);
PAINT ORANGE (700 5200);
DISPLAY INVISIBLE (700 5200);
FORCEPROP 1 LAST SIZE 1B
J 0
(745 5222);
DISPLAY 0.340426 (745 5222);
PAINT GREEN (745 5222);
DISPLAY INVISIBLE (745 5222);
FORCEPROP 1 LAST VOLTAGE 3.3V
J 0
(655 5157);
DISPLAY 0.340426 (655 5157);
PAINT SKYBLUE (655 5157);
DISPLAY INVISIBLE (655 5157);
FORCEPROP 1 LAST PATH I2
J 0
(745 5202);
DISPLAY 0.340426 (745 5202);
PAINT GREEN (745 5202);
DISPLAY INVISIBLE (745 5202);
FORCEADD RES..2
(700 4925);
FORCEPROP 1 LASTPIN (700 5025) $PN 1
J 0
(705 4987);
DISPLAY 0.617021 (705 4987);
PAINT ORANGE (705 4987);
FORCEPROP 1 LASTPIN (700 4825) $PN 2
J 0
(705 4835);
DISPLAY 0.617021 (705 4835);
PAINT ORANGE (705 4835);
FORCEPROP 1 LAST WATTAGE 1/16W
J 0
(740 4900);
DISPLAY 0.617021 (740 4900);
PAINT SKYBLUE (740 4900);
FORCEPROP 1 LAST MATERIAL CHIP
J 0
(740 4850);
DISPLAY 0.617021 (740 4850);
PAINT SKYBLUE (740 4850);
FORCEPROP 1 LAST PACK_TYPE 0402
J 0
(740 4750);
DISPLAY 0.617021 (740 4750);
PAINT SKYBLUE (740 4750);
FORCEPROP 1 LAST TOLERANCE 1%
J 0
(745 4950);
DISPLAY 0.617021 (745 4950);
PAINT SKYBLUE (745 4950);
FORCEPROP 1 LAST VALUE 4.75K
J 0
(745 5000);
DISPLAY 0.617021 (745 5000);
PAINT SKYBLUE (745 5000);
FORCEPROP 1 LAST PART_NUMBER G21796-072
J 0
(740 4800);
DISPLAY 0.617021 (740 4800);
PAINT BLUE (740 4800);
FORCEPROP 1 LAST LOCATION R2P17
J 0
(745 5050);
DISPLAY 0.617021 (745 5050);
PAINT AQUA (745 5050);
FORCEPROP 2 LAST ROOM THERMTRIP_PCH
J 0
(750 5100);
PAINT PEACH (750 5100);
DISPLAY INVISIBLE (750 5100);
FORCEPROP 2 LAST SEC 1
J 0
(750 5150);
DISPLAY 0.680851 (750 5150);
PAINT MONO (750 5150);
DISPLAY INVISIBLE (750 5150);
FORCEPROP 2 LAST SEC_TYPE 0402
J 0
(750 5150);
DISPLAY 1.021277 (750 5150);
PAINT ORANGE (750 5150);
DISPLAY INVISIBLE (750 5150);
FORCEPROP 2 LAST CDS_LIB mstr_discrete
J 0
(700 4925);
PAINT ORANGE (700 4925);
DISPLAY INVISIBLE (700 4925);
FORCEPROP 2 LAST BOM_COST SB
J 0
(750 5100);
PAINT MONO (750 5100);
DISPLAY INVISIBLE (750 5100);
FORCEPROP 1 LAST PATH I3
J 0
(750 5100);
DISPLAY 0.978723 (750 5100);
PAINT WHITE (750 5100);
DISPLAY INVISIBLE (750 5100);
FORCEADD OFFPAGE..4
(1850 3925);
FORCEPROP 2 LAST $XR1 126 
J 0
(2156 3925);
DISPLAY 0.638298 (2156 3925);
PAINT MONO (2156 3925);
FORCEPROP 2 LAST $XR0 119 
J 0
(2036 3925);
DISPLAY 0.638298 (2036 3925);
PAINT MONO (2036 3925);
FORCEPROP 1 LAST COMMENT_BODY TRUE
J 0
(1825 3825);
DISPLAY 0.872340 (1825 3825);
PAINT GREEN (1825 3825);
DISPLAY INVISIBLE (1825 3825);
FORCEPROP 1 LAST OFFPAGE TRUE
J 0
(2175 3800);
DISPLAY 0.872340 (2175 3800);
PAINT GREEN (2175 3800);
DISPLAY INVISIBLE (2175 3800);
FORCEPROP 2 LAST CDS_LIB mstr_standard
J 0
(1850 3925);
PAINT ORANGE (1850 3925);
DISPLAY INVISIBLE (1850 3925);
FORCEPROP 2 LAST PATH I5
J 0
(2175 3975);
DISPLAY 1.021277 (2175 3975);
PAINT ORANGE (2175 3975);
DISPLAY INVISIBLE (2175 3975);
FORCEADD OFFPAGE..1
(-500 4275);
FORCEPROP 2 LAST $XR3 184 
J 0
(-1112 4275);
DISPLAY 0.638298 (-1112 4275);
PAINT MONO (-1112 4275);
FORCEPROP 2 LAST $XR2 145 
J 0
(-992 4275);
DISPLAY 0.638298 (-992 4275);
PAINT MONO (-992 4275);
FORCEPROP 2 LAST $XR1 191 
J 0
(-872 4275);
DISPLAY 0.638298 (-872 4275);
PAINT MONO (-872 4275);
FORCEPROP 2 LAST $XR0 146 
J 0
(-752 4275);
DISPLAY 0.638298 (-752 4275);
PAINT MONO (-752 4275);
FORCEPROP 1 LAST COMMENT_BODY TRUE
J 0
(-375 4175);
DISPLAY 0.872340 (-375 4175);
PAINT GREEN (-375 4175);
DISPLAY INVISIBLE (-375 4175);
FORCEPROP 1 LAST OFFPAGE TRUE
J 0
(-175 4150);
DISPLAY 0.872340 (-175 4150);
PAINT GREEN (-175 4150);
DISPLAY INVISIBLE (-175 4150);
FORCEPROP 2 LAST CDS_LIB mstr_standard
J 0
(-500 4275);
PAINT ORANGE (-500 4275);
DISPLAY INVISIBLE (-500 4275);
FORCEPROP 2 LAST PATH I6
J 0
(-750 4325);
DISPLAY 1.021277 (-750 4325);
PAINT ORANGE (-750 4325);
DISPLAY INVISIBLE (-750 4325);
FORCEADD OFFPAGE..2
(-1925 4625);
FORCEPROP 2 LAST $XR0 118 
J 0
(-1736 4625);
DISPLAY 0.638298 (-1736 4625);
PAINT MONO (-1736 4625);
FORCEPROP 1 LAST COMMENT_BODY TRUE
J 0
(-1970 4530);
DISPLAY 1.170213 (-1970 4530);
PAINT GREEN (-1970 4530);
DISPLAY INVISIBLE (-1970 4530);
FORCEPROP 1 LAST OFFPAGE TRUE
J 0
(-1600 4500);
PAINT GREEN (-1600 4500);
DISPLAY INVISIBLE (-1600 4500);
FORCEPROP 2 LAST CDS_LIB mstr_standard
J 0
(-1925 4625);
PAINT MONO (-1925 4625);
DISPLAY INVISIBLE (-1925 4625);
FORCEPROP 2 LAST BOM_COST SB
J 0
(-1725 4675);
PAINT MONO (-1725 4675);
DISPLAY INVISIBLE (-1725 4675);
FORCEPROP 2 LAST PATH I7
J 0
(-1725 4675);
DISPLAY 1.021277 (-1725 4675);
PAINT ORANGE (-1725 4675);
DISPLAY INVISIBLE (-1725 4675);
FORCEADD P1V05_PCH_STBY..1
(-2875 5100);
FORCEPROP 3 LASTPIN (-2875 5050) SIG_NAME P1V05_PCH_STBY\g
J 0
(-2865 5060);
DISPLAY 0.659574 (-2865 5060);
PAINT MONO (-2865 5060);
DISPLAY INVISIBLE (-2865 5060);
FORCEPROP 1 LAST HDL_POWER P1V05_PCH_STBY
J 0
(-2875 5150);
DISPLAY 0.872340 (-2875 5150);
PAINT GREEN (-2875 5150);
DISPLAY INVISIBLE (-2875 5150);
FORCEPROP 1 LAST BODY_TYPE PLUMBING
J 0
(-2920 5057);
DISPLAY 0.340426 (-2920 5057);
PAINT GREEN (-2920 5057);
DISPLAY INVISIBLE (-2920 5057);
FORCEPROP 2 LAST CDS_LIB mstr_symbols
J 0
(-2875 5100);
PAINT ORANGE (-2875 5100);
DISPLAY INVISIBLE (-2875 5100);
FORCEPROP 1 LAST VOLTAGE 1.05V
J 0
(-2920 5057);
DISPLAY 0.340426 (-2920 5057);
PAINT SKYBLUE (-2920 5057);
DISPLAY INVISIBLE (-2920 5057);
FORCEPROP 1 LAST PATH I8
J 0
(-2825 5125);
DISPLAY 0.872340 (-2825 5125);
PAINT AQUA (-2825 5125);
DISPLAY INVISIBLE (-2825 5125);
FORCEADD RES..2
(-2875 4875);
FORCEPROP 1 LASTPIN (-2875 4975) $PN 1
J 0
(-2870 4937);
DISPLAY 0.617021 (-2870 4937);
PAINT ORANGE (-2870 4937);
FORCEPROP 1 LASTPIN (-2875 4775) $PN 2
J 0
(-2870 4785);
DISPLAY 0.617021 (-2870 4785);
PAINT ORANGE (-2870 4785);
FORCEPROP 1 LAST WATTAGE 1/16W
J 0
(-2835 4850);
DISPLAY 0.617021 (-2835 4850);
PAINT SKYBLUE (-2835 4850);
FORCEPROP 1 LAST MATERIAL CHIP
J 0
(-2835 4800);
DISPLAY 0.617021 (-2835 4800);
PAINT SKYBLUE (-2835 4800);
FORCEPROP 1 LAST PACK_TYPE 0402
J 0
(-2835 4700);
DISPLAY 0.617021 (-2835 4700);
PAINT SKYBLUE (-2835 4700);
FORCEPROP 1 LAST TOLERANCE 1%
J 0
(-2830 4900);
DISPLAY 0.617021 (-2830 4900);
PAINT SKYBLUE (-2830 4900);
FORCEPROP 1 LAST VALUE 10.0K
J 0
(-2830 4950);
DISPLAY 0.617021 (-2830 4950);
PAINT SKYBLUE (-2830 4950);
FORCEPROP 1 LAST LOCATION R7C21
J 0
(-2830 5000);
DISPLAY 0.617021 (-2830 5000);
PAINT AQUA (-2830 5000);
FORCEPROP 1 LAST PART_NUMBER G21796-016
J 0
(-2835 4750);
DISPLAY 0.617021 (-2835 4750);
PAINT BLUE (-2835 4750);
FORCEPROP 2 LAST ROOM THERMTRIP_PCH
J 0
(-2825 5050);
PAINT PEACH (-2825 5050);
DISPLAY INVISIBLE (-2825 5050);
FORCEPROP 2 LAST CDS_LOCATION R7C21
J 0
(-2830 5000);
DISPLAY 0.617021 (-2830 5000);
PAINT AQUA (-2830 5000);
DISPLAY INVISIBLE (-2830 5000);
FORCEPROP 2 LAST SEC 1
J 0
(-2825 5100);
DISPLAY 0.680851 (-2825 5100);
PAINT MONO (-2825 5100);
DISPLAY INVISIBLE (-2825 5100);
FORCEPROP 2 LAST CDS_LIB mstr_discrete
J 0
(-2875 4875);
PAINT ORANGE (-2875 4875);
DISPLAY INVISIBLE (-2875 4875);
FORCEPROP 2 LAST SEC_TYPE 0402
J 0
(-2825 5100);
DISPLAY 1.021277 (-2825 5100);
PAINT ORANGE (-2825 5100);
DISPLAY INVISIBLE (-2825 5100);
FORCEPROP 2 LAST BOM_COST SB
J 0
(-2825 5050);
PAINT MONO (-2825 5050);
DISPLAY INVISIBLE (-2825 5050);
FORCEPROP 1 LAST PATH I9
J 0
(-2825 5050);
DISPLAY 0.978723 (-2825 5050);
PAINT WHITE (-2825 5050);
DISPLAY INVISIBLE (-2825 5050);
FORCEADD INTEL_CORP_BPAGE..1
(2650 500);
FORCEPROP 1 LAST CDS_CON_LAST_MODIFIED Fri Jun 16 17:48:51 2017
J 0
(1225 825);
PAINT ORANGE (1225 825);
DISPLAY INVISIBLE (1225 825);
FORCEPROP 1 LAST CUSTOM_TXT_CDS <CURRENT_DESIGN_SHEET> OF <TOTAL_DESIGN_SHEETS>
J 0
(2150 525);
PAINT ORANGE (2150 525);
FORCEPROP 1 LAST CUSTOM_TXT_CDS <CON_LAST_MODIFIED>
J 0
(-1350 600);
PAINT ORANGE (-1350 600);
FORCEPROP 2 LAST CUSTOM_TXT_CDS <XR_PAGE_TITLE>
J 0
(-5240 5750);
DISPLAY 0.638298 (-5240 5750);
PAINT PINK (-5240 5750);
DISPLAY INVISIBLE (-5240 5750);
FORCEPROP 1 LAST SCH_TITLE THERMTRIP AND FIVRBREAK
J 0
(-5300 550);
DISPLAY 1.212766 (-5300 550);
PAINT ORANGE (-5300 550);
FORCEPROP 1 LAST COMMENT_BODY TRUE
J 0
(2662 512);
DISPLAY 0.468085 (2662 512);
PAINT GREEN (2662 512);
DISPLAY INVISIBLE (2662 512);
FORCEPROP 2 LAST PAGE_BORDER TRUE
J 0
(-5240 5750);
DISPLAY 0.851064 (-5240 5750);
PAINT PINK (-5240 5750);
DISPLAY INVISIBLE (-5240 5750);
FORCEPROP 2 LAST CDS_LIB mstr_symbols
J 0
(2650 500);
PAINT MONO (2650 500);
DISPLAY INVISIBLE (2650 500);
FORCEPROP 2 LAST CDS_XR_PAGE_TITLE CR-134 : @BASEBOARD_FAB2_LIB.BASEBOARD_FAB2(SCH_1):PAGE134
J 0
(-5240 5750);
DISPLAY 0.638298 (-5240 5750);
PAINT PINK (-5240 5750);
DISPLAY INVISIBLE (-5240 5750);
WIRE 16 -1 (-2875 4200)(-2875 4000);
WIRE 16 -1 (700 5150)(700 5025);
WIRE 16 -1 (-2875 4975)(-2875 5050);
WIRE 16 273 (-5175 3025)(2375 3025);
WIRE 16 -1 (-4600 4300)(-4050 4300);
WIRE 16 -1 (-3850 4300)(-3075 4300);
FORCEPROP 2 LAST SIG_NAME FM_THERMTRIP_DLY_R
J 0
(-3785 4310);
DISPLAY 0.617021 (-3785 4310);
PAINT ORANGE (-3785 4310);
FORCEPROP 2 LASTPROP $XRERR UNIQUE?
J 0
(-4025 4310);
DISPLAY 0.638298 (-4025 4310);
PAINT MONO (-4025 4310);
DISPLAY INVISIBLE (-4025 4310);
WIRE 16 -1 (-2875 4625)(-2875 4600);
WIRE 16 -1 (-2875 4775)(-2875 4625);
WIRE 16 -1 (-1975 4625)(-2875 4625);
FORCEPROP 2 LAST SIG_NAME FM_PCH_LVC1_THERMTRIP_N
J 0
(-2710 4635);
DISPLAY 0.617021 (-2710 4635);
PAINT ORANGE (-2710 4635);
WIRE 16 -1 (500 4275)(-450 4275);
FORCEPROP 2 LAST SIG_NAME RST_PLTRST_BUF_N
J 0
(-360 4285);
DISPLAY 0.617021 (-360 4285);
PAINT ORANGE (-360 4285);
WIRE 16 -1 (700 4825)(700 4650);
WIRE 16 -1 (700 4650)(1825 4650);
FORCEPROP 2 LAST SIG_NAME FM_PCH_BMC_THERMTRIP_N
J 0
(990 4660);
DISPLAY 0.617021 (990 4660);
PAINT ORANGE (990 4660);
WIRE 16 -1 (700 4575)(700 4650);
WIRE 16 -1 (700 3925)(1800 3925);
FORCEPROP 2 LAST SIG_NAME FM_PCH_BMC_THERMTRIP_EXI_STRAP_N
J 0
(965 3935);
DISPLAY 0.617021 (965 3935);
PAINT ORANGE (965 3935);
WIRE 16 -1 (700 4175)(700 3925);
DOT 1 (-2875 4625);
DOT 1 (700 4650);
QUIT
